# TIMECARD (Time Appliance Project (Time Card)) — schematic netlist excerpt (pin names and nets, part order shuffled) for the footprints in the layout excerpt that follows; sources: Cadence DE-HDL packaged netlist, KiCad conversion of R4006-B0001-02_R01.brd

R19  RESISTOR  10KOHM 1%  pkg SMC_0402R_H016  page 16 : \1\ = XP3R3V_FPGA ; \2\ = EEPROM_SCL

U23  MT25QL128ABA1ESE_SOP8  MT25QL128ABA1ESE-0SIT  pkg SOP8_208_P050_V2  page 10
  \s*\  = FLASH_CS_N
  DQ1  = UNNAMED_127_MT25QL128ABA1ESES_1
  \w/dq2*\  = UNNAMED_127_MT25QL128ABA1ESES_3
  VSS  = SG
  DQ0  = UNNAMED_127_MT25QL128ABA1ESESOP
  C  = FLASH_CLK
  \hold/dq3*\  = UNNAMED_127_MT25QL128ABA1ESES_2
  VCC  = XP3R3V_FPGA

(kicad_pcb
	(version 20260206)
	(generator "pcbnew")
	(generator_version "10.0")
	(general
		(thickness 1.6)
		(legacy_teardrops no)
	)
	(paper "A4")
	(title_block
		(title "timecard-production-celestica-r4006 — R4006-B0001-02_R01.brd")
		(comment 1 "Time Appliance Project (Time Card) / footprints 28-29 of 1113")
	)
	(layers
		(0 "F.Cu" signal "TOP")
		(4 "In1.Cu" signal "L02_GND1")
		(6 "In2.Cu" signal "L03_SIG1")
		(8 "In3.Cu" signal "L04_GND2")
		(10 "In4.Cu" signal "L05_VCC1")
		(12 "In5.Cu" signal "L06_VCC2")
		(14 "In6.Cu" signal "L07_GND3")
		(16 "In7.Cu" signal "L08_SIG2")
		(18 "In8.Cu" signal "L09_GND4")
		(2 "B.Cu" signal "BOTTOM")
		(9 "F.Adhes" user "F.Adhesive")
		(11 "B.Adhes" user "B.Adhesive")
		(13 "F.Paste" user "Package Geometry/Pastemask Top")
		(15 "B.Paste" user "Package Geometry/Pastemask Bottom")
		(5 "F.SilkS" user "Ref Des/Silkscreen Top")
		(7 "B.SilkS" user "Ref Des/Silkscreen Bottom")
		(1 "F.Mask" user "Board Geometry/Soldermask Top")
		(3 "B.Mask" user "Board Geometry/Soldermask Bottom")
		(17 "Dwgs.User" user "User.Drawings")
		(19 "Cmts.User" user "User.Comments")
		(21 "Eco1.User" user "User.Eco1")
		(23 "Eco2.User" user "User.Eco2")
		(25 "Edge.Cuts" user "Board Geometry/Outline")
		(27 "Margin" user)
		(31 "F.CrtYd" user "Package Geometry/Place Bound Top")
		(29 "B.CrtYd" user "Package Geometry/Place Bound Bottom")
		(35 "F.Fab" user "Ref Des/Assembly Top")
		(33 "B.Fab" user "Ref Des/Assembly Bottom")
	)
	(footprint ""
		(layer "F.Cu")
		(at 30.34538 -17.99844 180)
		(property "Reference" "R19"
			(at 1.27 5.04063 0)
			(unlocked yes)
			(layer "F.SilkS")
			(effects
				(font
					(size 0.7874 0.5842)
					(thickness 0.1524)
				)
			)
		)
		(property "Value" "VAL*"
			(at 0.02032 2.13233 180)
			(unlocked yes)
			(layer "F.Fab")
			(hide yes)
			(effects
				(font
					(size 0.7874 0.5842)
					(thickness 0.1524)
				)
			)
		)
		(property "Tolerance" "TOL*"
			(at 0.044704 3.05435 180)
			(unlocked yes)
			(layer "Cmts.User")
			(hide yes)
			(effects
				(font
					(size 0.7874 0.5842)
					(thickness 0.1524)
				)
			)
		)
		(property "User Part Number" "PARTNUM*"
			(at 0.02032 4.024884 180)
			(unlocked yes)
			(layer "Cmts.User")
			(hide yes)
			(effects
				(font
					(size 0.7874 0.5842)
					(thickness 0.1524)
				)
			)
		)
		(property "Device Type" "RESISTOR-G155-11002-01,10KOHM,A"
			(at 0.008382 1.210564 180)
			(unlocked yes)
			(layer "F.Fab")
			(hide yes)
			(effects
				(font
					(size 0.7874 0.5842)
					(thickness 0.1524)
				)
			)
		)
		(duplicate_pad_numbers_are_jumpers no)
		(fp_line
			(start 1.143 0.5588)
			(end 1.143 -0.5588)
			(stroke
				(width 0.1)
				(type default)
			)
			(layer "F.SilkS")
		)
		(fp_line
			(start 1.143 -0.5588)
			(end -1.143 -0.5588)
			(stroke
				(width 0.1)
				(type default)
			)
			(layer "F.SilkS")
		)
		(fp_line
			(start -1.143 0.5588)
			(end 1.143 0.5588)
			(stroke
				(width 0.1)
				(type default)
			)
			(layer "F.SilkS")
		)
		(fp_line
			(start -1.143 -0.5588)
			(end -1.143 0.5588)
			(stroke
				(width 0.1)
				(type default)
			)
			(layer "F.SilkS")
		)
		(fp_rect
			(start 1.143 -0.5588)
			(end -1.143 0.5588)
			(stroke
				(width 0)
				(type default)
			)
			(fill no)
			(layer "F.CrtYd")
		)
		(fp_line
			(start 0.508 0.3048)
			(end 0.508 -0.3048)
			(stroke
				(width 0.1)
				(type default)
			)
			(layer "F.Fab")
		)
		(fp_line
			(start 0.508 -0.3048)
			(end -0.508 -0.3048)
			(stroke
				(width 0.1)
				(type default)
			)
			(layer "F.Fab")
		)
		(fp_line
			(start -0.508 0.3048)
			(end 0.508 0.3048)
			(stroke
				(width 0.1)
				(type default)
			)
			(layer "F.Fab")
		)
		(fp_line
			(start -0.508 -0.3048)
			(end -0.508 0.3048)
			(stroke
				(width 0.1)
				(type default)
			)
			(layer "F.Fab")
		)
		(pad "1" smd rect
			(at -0.5334 0 180)
			(size 0.7112 0.6096)
			(layers "F.Cu" "F.Mask" "F.Paste")
			(net "XP3R3V_FPGA")
		)
		(pad "2" smd rect
			(at 0.5334 0 180)
			(size 0.7112 0.6096)
			(layers "F.Cu" "F.Mask" "F.Paste")
			(net "EEPROM_SCL")
		)
		(zone
			(layer "F.Cu")
			(hatch none 0.5)
			(connect_pads
				(clearance 0)
			)
			(min_thickness 0.25)
			(keepout
				(tracks allowed)
				(vias not_allowed)
				(pads allowed)
				(copperpour not_allowed)
				(footprints allowed)
			)
			(placement
				(enabled no)
				(sheetname "")
			)
			(fill
				(thermal_gap 0.5)
				(thermal_bridge_width 0.5)
				(island_removal_mode 0)
			)
			(polygon
				(pts
					(xy 30.26918 -17.69364) (xy 30.42158 -17.69364) (xy 30.42158 -18.30324) (xy 30.26918 -18.30324)
				)
			)
		)
	)
	(footprint ""
		(layer "F.Cu")
		(at 92.075 -84.074 180)
		(property "Reference" "U23"
			(at -0.5334 -3.79857 0)
			(unlocked yes)
			(layer "F.SilkS")
			(effects
				(font
					(size 0.7874 0.5842)
					(thickness 0.1524)
				)
			)
		)
		(property "Value" ""
			(at 0 0 180)
			(layer "F.Fab")
			(effects
				(font
					(size 1.27 1.27)
				)
			)
		)
		(property "User Part Number" "PARTNUM*"
			(at 0 5.133848 180)
			(unlocked yes)
			(layer "Cmts.User")
			(hide yes)
			(effects
				(font
					(size 0.7874 0.5842)
					(thickness 0.1524)
				)
			)
		)
		(property "Device Type" "MT25QL128ABA1ESE_SOP8-G221-102A"
			(at 0 4.092448 180)
			(unlocked yes)
			(layer "F.Fab")
			(hide yes)
			(effects
				(font
					(size 0.7874 0.5842)
					(thickness 0.1524)
				)
			)
		)
		(duplicate_pad_numbers_are_jumpers no)
		(fp_line
			(start 4.826 2.998978)
			(end 4.826 -2.998978)
			(stroke
				(width 0.1)
				(type default)
			)
			(layer "F.SilkS")
		)
		(fp_line
			(start 4.826 -2.998978)
			(end -4.826 -2.998978)
			(stroke
				(width 0.1)
				(type default)
			)
			(layer "F.SilkS")
		)
		(fp_line
			(start -4.826 2.998978)
			(end 4.826 2.998978)
			(stroke
				(width 0.1)
				(type default)
			)
			(layer "F.SilkS")
		)
		(fp_line
			(start -4.826 -2.998978)
			(end -4.826 2.998978)
			(stroke
				(width 0.1)
				(type default)
			)
			(layer "F.SilkS")
		)
		(fp_poly
			(pts
				(arc
					(start -5.969 -3.429)
					(mid -5.207 -3.429)
					(end -5.969 -3.429)
				)
			)
			(stroke
				(width 0)
				(type default)
			)
			(fill yes)
			(layer "F.SilkS")
		)
		(fp_rect
			(start 5.08 -3.252978)
			(end -5.08 3.252978)
			(stroke
				(width 0)
				(type default)
			)
			(fill no)
			(layer "F.CrtYd")
		)
		(fp_line
			(start 2.744978 2.744978)
			(end 2.744978 -2.744978)
			(stroke
				(width 0.1)
				(type default)
			)
			(layer "F.Fab")
		)
		(fp_line
			(start 2.744978 -2.744978)
			(end -2.744978 -2.744978)
			(stroke
				(width 0.1)
				(type default)
			)
			(layer "F.Fab")
		)
		(fp_line
			(start -2.744978 2.744978)
			(end 2.744978 2.744978)
			(stroke
				(width 0.1)
				(type default)
			)
			(layer "F.Fab")
		)
		(fp_line
			(start -2.744978 -2.744978)
			(end -2.744978 2.744978)
			(stroke
				(width 0.1)
				(type default)
			)
			(layer "F.Fab")
		)
		(fp_circle
			(center -4.133342 -2.39014)
			(end -4.514342 -2.39014)
			(stroke
				(width 0.1)
				(type default)
			)
			(fill no)
			(layer "F.Fab")
		)
		(fp_text user "5"
			(at 4.1656 3.82143 0)
			(unlocked yes)
			(layer "F.SilkS")
			(effects
				(font
					(size 0.7874 0.5842)
					(thickness 0.1524)
				)
			)
		)
		(fp_text user "8"
			(at 3.9116 -3.92557 0)
			(unlocked yes)
			(layer "F.SilkS")
			(effects
				(font
					(size 0.7874 0.5842)
					(thickness 0.1524)
				)
			)
		)
		(fp_text user "4"
			(at -5.3594 1.84785 0)
			(unlocked yes)
			(layer "F.SilkS")
			(effects
				(font
					(size 0.635 0.4064)
					(thickness 0.1524)
				)
			)
		)
		(fp_text user "5"
			(at 3.683 1.49733 0)
			(unlocked yes)
			(layer "F.Fab")
			(effects
				(font
					(size 0.7874 0.5842)
					(thickness 0.1524)
				)
			)
		)
		(fp_text user "8"
			(at 3.683 -2.31267 0)
			(unlocked yes)
			(layer "F.Fab")
			(effects
				(font
					(size 0.7874 0.5842)
					(thickness 0.1524)
				)
			)
		)
		(fp_text user "4"
			(at -3.4544 2.31013 0)
			(unlocked yes)
			(layer "F.Fab")
			(effects
				(font
					(size 0.7874 0.5842)
					(thickness 0.1524)
				)
			)
		)
		(pad "1" smd rect
			(at -3.6576 -1.905 180)
			(size 1.8288 0.508)
			(layers "F.Cu" "F.Mask" "F.Paste")
			(net "FLASH_CS_N")
		)
		(pad "2" smd rect
			(at -3.6576 -0.635 180)
			(size 1.8288 0.508)
			(layers "F.Cu" "F.Mask" "F.Paste")
			(net "UNNAMED_127_MT25QL128ABA1ESES_1")
		)
		(pad "3" smd rect
			(at -3.6576 0.635 180)
			(size 1.8288 0.508)
			(layers "F.Cu" "F.Mask" "F.Paste")
			(net "UNNAMED_127_MT25QL128ABA1ESES_3")
		)
		(pad "4" smd rect
			(at -3.6576 1.905 180)
			(size 1.8288 0.508)
			(layers "F.Cu" "F.Mask" "F.Paste")
			(net "SG")
		)
		(pad "5" smd rect
			(at 3.6576 1.905 180)
			(size 1.8288 0.508)
			(layers "F.Cu" "F.Mask" "F.Paste")
			(net "UNNAMED_127_MT25QL128ABA1ESESOP")
		)
		(pad "6" smd rect
			(at 3.6576 0.635 180)
			(size 1.8288 0.508)
			(layers "F.Cu" "F.Mask" "F.Paste")
			(net "FLASH_CLK")
		)
		(pad "7" smd rect
			(at 3.6576 -0.635 180)
			(size 1.8288 0.508)
			(layers "F.Cu" "F.Mask" "F.Paste")
			(net "UNNAMED_127_MT25QL128ABA1ESES_2")
		)
		(pad "8" smd rect
			(at 3.6576 -1.905 180)
			(size 1.8288 0.508)
			(layers "F.Cu" "F.Mask" "F.Paste")
			(net "XP3R3V_FPGA")
		)
	)
)
